(kicad_pcb
	(version 20260206)
	(generator "pcbnew")
	(generator_version "10.0")
	(general
		(thickness 1.6)
		(legacy_teardrops no)
	)
	(paper "A4")
	(title_block
		(title "04192023_DAF0TMB3IC0_F0TG_MB_C_brd_V02_OCP.brd")
		(comment 1 "Grand Teton / footprints 7943-7950 of 8354")
	)
	(layers
		(0 "F.Cu" signal "TOP")
		(4 "In1.Cu" signal "GND")
		(6 "In2.Cu" signal "IN1")
		(8 "In3.Cu" signal "GND1")
		(10 "In4.Cu" signal "IN2")
		(12 "In5.Cu" signal "GND2")
		(14 "In6.Cu" signal "IN3")
		(16 "In7.Cu" signal "GND3")
		(18 "In8.Cu" signal "VCC")
		(20 "In9.Cu" signal "VCC1")
		(22 "In10.Cu" signal "GND4")
		(24 "In11.Cu" signal "IN4")
		(26 "In12.Cu" signal "GND5")
		(28 "In13.Cu" signal "IN5")
		(30 "In14.Cu" signal "GND6")
		(32 "In15.Cu" signal "IN6")
		(34 "In16.Cu" signal "GND7")
		(2 "B.Cu" signal "BOTTOM")
		(9 "F.Adhes" user "F.Adhesive")
		(11 "B.Adhes" user "B.Adhesive")
		(13 "F.Paste" user "Package Geometry/Pastemask Top")
		(15 "B.Paste" user "Package Geometry/Pastemask Bottom")
		(5 "F.SilkS" user "Ref Des/Silkscreen Top")
		(7 "B.SilkS" user "Ref Des/Silkscreen Bottom")
		(1 "F.Mask" user "Board Geometry/Soldermask Top")
		(3 "B.Mask" user "Board Geometry/Soldermask Bottom")
		(17 "Dwgs.User" user "User.Drawings")
		(19 "Cmts.User" user "User.Comments")
		(21 "Eco1.User" user "User.Eco1")
		(23 "Eco2.User" user "User.Eco2")
		(25 "Edge.Cuts" user "Board Geometry/Outline")
		(27 "Margin" user)
		(31 "F.CrtYd" user "Package Geometry/Place Bound Top")
		(29 "B.CrtYd" user "Package Geometry/Place Bound Bottom")
		(35 "F.Fab" user "Ref Des/Assembly Top")
		(33 "B.Fab" user "Ref Des/Assembly Bottom")
	)
	(footprint ""
		(layer "B.Cu")
		(at 358.796082 -258.795012 180)
		(property "Reference" "C2616"
			(at 0 0 0)
			(layer "B.SilkS")
			(hide yes)
			(effects
				(font
					(size 1.27 1.27)
				)
				(justify mirror)
			)
		)
		(property "Value" ""
			(at 0 0 0)
			(layer "B.Fab")
			(effects
				(font
					(size 1.27 1.27)
				)
				(justify mirror)
			)
		)
		(duplicate_pad_numbers_are_jumpers no)
		(fp_line
			(start 0.7874 0.4064)
			(end 0.7874 -0.4064)
			(stroke
				(width 0.1524)
				(type default)
			)
			(layer "B.SilkS")
		)
		(fp_line
			(start 0.7874 -0.4064)
			(end -0.7874 -0.4064)
			(stroke
				(width 0.1524)
				(type default)
			)
			(layer "B.SilkS")
		)
		(fp_line
			(start -0.7874 0.4064)
			(end 0.7874 0.4064)
			(stroke
				(width 0.1524)
				(type default)
			)
			(layer "B.SilkS")
		)
		(fp_line
			(start -0.7874 -0.4064)
			(end -0.7874 0.4064)
			(stroke
				(width 0.1524)
				(type default)
			)
			(layer "B.SilkS")
		)
		(fp_line
			(start 0.67945 0.3048)
			(end 0.67945 -0.305054)
			(stroke
				(width 0.1)
				(type default)
			)
			(layer "B.Fab")
		)
		(fp_line
			(start 0.67945 -0.305054)
			(end 0.12065 -0.305054)
			(stroke
				(width 0.1)
				(type default)
			)
			(layer "B.Fab")
		)
		(fp_line
			(start 0.12065 0.3048)
			(end 0.67945 0.3048)
			(stroke
				(width 0.1)
				(type default)
			)
			(layer "B.Fab")
		)
		(fp_line
			(start 0.12065 0.2794)
			(end 0.12065 0.3048)
			(stroke
				(width 0.1)
				(type default)
			)
			(layer "B.Fab")
		)
		(fp_line
			(start 0.12065 -0.2794)
			(end -0.12065 -0.2794)
			(stroke
				(width 0.1)
				(type default)
			)
			(layer "B.Fab")
		)
		(fp_line
			(start 0.12065 -0.305054)
			(end 0.12065 -0.2794)
			(stroke
				(width 0.1)
				(type default)
			)
			(layer "B.Fab")
		)
		(fp_line
			(start -0.120396 0.3048)
			(end -0.120396 0.2794)
			(stroke
				(width 0.1)
				(type default)
			)
			(layer "B.Fab")
		)
		(fp_line
			(start -0.120396 0.2794)
			(end 0.12065 0.2794)
			(stroke
				(width 0.1)
				(type default)
			)
			(layer "B.Fab")
		)
		(fp_line
			(start -0.12065 -0.2794)
			(end -0.12065 -0.3048)
			(stroke
				(width 0.1)
				(type default)
			)
			(layer "B.Fab")
		)
		(fp_line
			(start -0.12065 -0.3048)
			(end -0.67945 -0.3048)
			(stroke
				(width 0.1)
				(type default)
			)
			(layer "B.Fab")
		)
		(fp_line
			(start -0.67945 0.3048)
			(end -0.120396 0.3048)
			(stroke
				(width 0.1)
				(type default)
			)
			(layer "B.Fab")
		)
		(fp_line
			(start -0.67945 -0.3048)
			(end -0.67945 0.3048)
			(stroke
				(width 0.1)
				(type default)
			)
			(layer "B.Fab")
		)
		(pad "1" smd circle
			(at 0.40005 0)
			(size 0 0)
			(layers "B.Cu" "B.Mask" "B.Paste")
			(net "PVDD11_S3_P0")
		)
		(pad "2" smd circle
			(at -0.40005 0)
			(size 0 0)
			(layers "B.Cu" "B.Mask" "B.Paste")
			(net "GND")
		)
	)
	(footprint ""
		(layer "B.Cu")
		(at 244.475 -229.489)
		(property "Reference" "R406"
			(at 0 0 0)
			(layer "B.SilkS")
			(hide yes)
			(effects
				(font
					(size 1.27 1.27)
				)
				(justify mirror)
			)
		)
		(property "Value" ""
			(at 0 0 0)
			(layer "B.Fab")
			(effects
				(font
					(size 1.27 1.27)
				)
				(justify mirror)
			)
		)
		(duplicate_pad_numbers_are_jumpers no)
		(fp_line
			(start -0.7874 -0.4064)
			(end -0.7874 0.4064)
			(stroke
				(width 0.1524)
				(type default)
			)
			(layer "B.SilkS")
		)
		(fp_line
			(start -0.7874 0.4064)
			(end 0.7874 0.4064)
			(stroke
				(width 0.1524)
				(type default)
			)
			(layer "B.SilkS")
		)
		(fp_line
			(start 0.7874 -0.4064)
			(end -0.7874 -0.4064)
			(stroke
				(width 0.1524)
				(type default)
			)
			(layer "B.SilkS")
		)
		(fp_line
			(start 0.7874 0.4064)
			(end 0.7874 -0.4064)
			(stroke
				(width 0.1524)
				(type default)
			)
			(layer "B.SilkS")
		)
		(fp_line
			(start -0.67945 -0.3048)
			(end -0.67945 0.3048)
			(stroke
				(width 0.1)
				(type default)
			)
			(layer "B.Fab")
		)
		(fp_line
			(start -0.67945 0.3048)
			(end -0.120396 0.3048)
			(stroke
				(width 0.1)
				(type default)
			)
			(layer "B.Fab")
		)
		(fp_line
			(start -0.12065 -0.3048)
			(end -0.67945 -0.3048)
			(stroke
				(width 0.1)
				(type default)
			)
			(layer "B.Fab")
		)
		(fp_line
			(start -0.12065 -0.2794)
			(end -0.12065 -0.3048)
			(stroke
				(width 0.1)
				(type default)
			)
			(layer "B.Fab")
		)
		(fp_line
			(start -0.120396 0.2794)
			(end 0.12065 0.2794)
			(stroke
				(width 0.1)
				(type default)
			)
			(layer "B.Fab")
		)
		(fp_line
			(start -0.120396 0.3048)
			(end -0.120396 0.2794)
			(stroke
				(width 0.1)
				(type default)
			)
			(layer "B.Fab")
		)
		(fp_line
			(start 0.12065 -0.305054)
			(end 0.12065 -0.2794)
			(stroke
				(width 0.1)
				(type default)
			)
			(layer "B.Fab")
		)
		(fp_line
			(start 0.12065 -0.2794)
			(end -0.12065 -0.2794)
			(stroke
				(width 0.1)
				(type default)
			)
			(layer "B.Fab")
		)
		(fp_line
			(start 0.12065 0.2794)
			(end 0.12065 0.3048)
			(stroke
				(width 0.1)
				(type default)
			)
			(layer "B.Fab")
		)
		(fp_line
			(start 0.12065 0.3048)
			(end 0.67945 0.3048)
			(stroke
				(width 0.1)
				(type default)
			)
			(layer "B.Fab")
		)
		(fp_line
			(start 0.67945 -0.305054)
			(end 0.12065 -0.305054)
			(stroke
				(width 0.1)
				(type default)
			)
			(layer "B.Fab")
		)
		(fp_line
			(start 0.67945 0.3048)
			(end 0.67945 -0.305054)
			(stroke
				(width 0.1)
				(type default)
			)
			(layer "B.Fab")
		)
		(pad "1" smd circle
			(at 0.40005 0 180)
			(size 0 0)
			(layers "B.Cu" "B.Mask" "B.Paste")
			(net "PVDD18_S5_P0")
		)
		(pad "2" smd circle
			(at -0.40005 0 180)
			(size 0 0)
			(layers "B.Cu" "B.Mask" "B.Paste")
			(net "SMB_CPU0_CPU1_SEC_SDA_R2")
		)
	)
	(footprint ""
		(layer "B.Cu")
		(at 338.306156 -395.148562 90)
		(property "Reference" "C654"
			(at 0 0 90)
			(layer "B.SilkS")
			(hide yes)
			(effects
				(font
					(size 1.27 1.27)
				)
				(justify mirror)
			)
		)
		(property "Value" ""
			(at 0 0 90)
			(layer "B.Fab")
			(effects
				(font
					(size 1.27 1.27)
				)
				(justify mirror)
			)
		)
		(duplicate_pad_numbers_are_jumpers no)
		(fp_line
			(start 0.299974 -0.150114)
			(end -0.299974 -0.150114)
			(stroke
				(width 0.1)
				(type default)
			)
			(layer "B.Fab")
		)
		(fp_line
			(start -0.299974 -0.150114)
			(end -0.299974 0.150114)
			(stroke
				(width 0.1)
				(type default)
			)
			(layer "B.Fab")
		)
		(fp_line
			(start 0.299974 0.150114)
			(end 0.299974 -0.150114)
			(stroke
				(width 0.1)
				(type default)
			)
			(layer "B.Fab")
		)
		(fp_line
			(start -0.299974 0.150114)
			(end 0.299974 0.150114)
			(stroke
				(width 0.1)
				(type default)
			)
			(layer "B.Fab")
		)
		(pad "1" smd rect
			(at 0.2667 0 270)
			(size 0.3048 0.381)
			(layers "B.Cu" "B.Mask" "B.Paste")
			(net "P0V9_CPU0_RT1_2A")
		)
		(pad "2" smd rect
			(at -0.2667 0 270)
			(size 0.3048 0.381)
			(layers "B.Cu" "B.Mask" "B.Paste")
			(net "GND")
		)
	)
	(footprint ""
		(layer "B.Cu")
		(at 185.240676 -13.60043 -90)
		(property "Reference" "R6005"
			(at 0 0 90)
			(layer "B.SilkS")
			(hide yes)
			(effects
				(font
					(size 1.27 1.27)
				)
				(justify mirror)
			)
		)
		(property "Value" ""
			(at 0 0 90)
			(layer "B.Fab")
			(effects
				(font
					(size 1.27 1.27)
				)
				(justify mirror)
			)
		)
		(duplicate_pad_numbers_are_jumpers no)
		(fp_line
			(start -0.7874 0.4064)
			(end 0.7874 0.4064)
			(stroke
				(width 0.1524)
				(type default)
			)
			(layer "B.SilkS")
		)
		(fp_line
			(start 0.7874 0.4064)
			(end 0.7874 -0.4064)
			(stroke
				(width 0.1524)
				(type default)
			)
			(layer "B.SilkS")
		)
		(fp_line
			(start -0.7874 -0.4064)
			(end -0.7874 0.4064)
			(stroke
				(width 0.1524)
				(type default)
			)
			(layer "B.SilkS")
		)
		(fp_line
			(start 0.7874 -0.4064)
			(end -0.7874 -0.4064)
			(stroke
				(width 0.1524)
				(type default)
			)
			(layer "B.SilkS")
		)
		(fp_line
			(start -0.67945 0.3048)
			(end -0.120396 0.3048)
			(stroke
				(width 0.1)
				(type default)
			)
			(layer "B.Fab")
		)
		(fp_line
			(start -0.120396 0.3048)
			(end -0.120396 0.2794)
			(stroke
				(width 0.1)
				(type default)
			)
			(layer "B.Fab")
		)
		(fp_line
			(start 0.12065 0.3048)
			(end 0.67945 0.3048)
			(stroke
				(width 0.1)
				(type default)
			)
			(layer "B.Fab")
		)
		(fp_line
			(start 0.67945 0.3048)
			(end 0.67945 -0.305054)
			(stroke
				(width 0.1)
				(type default)
			)
			(layer "B.Fab")
		)
		(fp_line
			(start -0.120396 0.2794)
			(end 0.12065 0.2794)
			(stroke
				(width 0.1)
				(type default)
			)
			(layer "B.Fab")
		)
		(fp_line
			(start 0.12065 0.2794)
			(end 0.12065 0.3048)
			(stroke
				(width 0.1)
				(type default)
			)
			(layer "B.Fab")
		)
		(fp_line
			(start -0.12065 -0.2794)
			(end -0.12065 -0.3048)
			(stroke
				(width 0.1)
				(type default)
			)
			(layer "B.Fab")
		)
		(fp_line
			(start 0.12065 -0.2794)
			(end -0.12065 -0.2794)
			(stroke
				(width 0.1)
				(type default)
			)
			(layer "B.Fab")
		)
		(fp_line
			(start -0.67945 -0.3048)
			(end -0.67945 0.3048)
			(stroke
				(width 0.1)
				(type default)
			)
			(layer "B.Fab")
		)
		(fp_line
			(start -0.12065 -0.3048)
			(end -0.67945 -0.3048)
			(stroke
				(width 0.1)
				(type default)
			)
			(layer "B.Fab")
		)
		(fp_line
			(start 0.12065 -0.305054)
			(end 0.12065 -0.2794)
			(stroke
				(width 0.1)
				(type default)
			)
			(layer "B.Fab")
		)
		(fp_line
			(start 0.67945 -0.305054)
			(end 0.12065 -0.305054)
			(stroke
				(width 0.1)
				(type default)
			)
			(layer "B.Fab")
		)
		(pad "1" smd circle
			(at 0.40005 0 90)
			(size 0 0)
			(layers "B.Cu" "B.Mask" "B.Paste")
			(net "I3C_SCM_2_SDA")
		)
		(pad "2" smd circle
			(at -0.40005 0 90)
			(size 0 0)
			(layers "B.Cu" "B.Mask" "B.Paste")
			(net "I3C_SCM_2_R_SDA")
		)
	)
	(footprint ""
		(layer "B.Cu")
		(at 152.202642 -80.81518)
		(property "Reference" "PC867"
			(at 0 0 0)
			(layer "B.SilkS")
			(hide yes)
			(effects
				(font
					(size 1.27 1.27)
				)
				(justify mirror)
			)
		)
		(property "Value" ""
			(at 0 0 0)
			(layer "B.Fab")
			(effects
				(font
					(size 1.27 1.27)
				)
				(justify mirror)
			)
		)
		(duplicate_pad_numbers_are_jumpers no)
		(fp_line
			(start -1.524 -0.762)
			(end -1.524 0.762)
			(stroke
				(width 0.1524)
				(type default)
			)
			(layer "B.SilkS")
		)
		(fp_line
			(start -1.524 0.762)
			(end 1.524 0.762)
			(stroke
				(width 0.1524)
				(type default)
			)
			(layer "B.SilkS")
		)
		(fp_line
			(start 1.524 -0.762)
			(end -1.524 -0.762)
			(stroke
				(width 0.1524)
				(type default)
			)
			(layer "B.SilkS")
		)
		(fp_line
			(start 1.524 0.762)
			(end 1.524 -0.762)
			(stroke
				(width 0.1524)
				(type default)
			)
			(layer "B.SilkS")
		)
		(fp_line
			(start -1.1049 -0.724916)
			(end 1.1049 -0.724916)
			(stroke
				(width 0.1)
				(type default)
			)
			(layer "B.Fab")
		)
		(fp_line
			(start -1.1049 0.724916)
			(end -1.1049 -0.724916)
			(stroke
				(width 0.1)
				(type default)
			)
			(layer "B.Fab")
		)
		(fp_line
			(start 1.1049 -0.724916)
			(end 1.1049 0.724916)
			(stroke
				(width 0.1)
				(type default)
			)
			(layer "B.Fab")
		)
		(fp_line
			(start 1.1049 0.724916)
			(end -1.1049 0.724916)
			(stroke
				(width 0.1)
				(type default)
			)
			(layer "B.Fab")
		)
		(pad "1" smd rect
			(at 0.889 0)
			(size 1.016 1.27)
			(layers "B.Cu" "B.Mask" "B.Paste")
			(net "P1V8_AUX")
		)
		(pad "2" smd rect
			(at -0.889 0)
			(size 1.016 1.27)
			(layers "B.Cu" "B.Mask" "B.Paste")
			(net "GND")
		)
	)
	(footprint ""
		(layer "B.Cu")
		(at 365.835692 -260.305042)
		(property "Reference" "C2531"
			(at 0 0 0)
			(layer "B.SilkS")
			(hide yes)
			(effects
				(font
					(size 1.27 1.27)
				)
				(justify mirror)
			)
		)
		(property "Value" ""
			(at 0 0 0)
			(layer "B.Fab")
			(effects
				(font
					(size 1.27 1.27)
				)
				(justify mirror)
			)
		)
		(duplicate_pad_numbers_are_jumpers no)
		(fp_line
			(start -0.7874 -0.4064)
			(end -0.7874 0.4064)
			(stroke
				(width 0.1524)
				(type default)
			)
			(layer "B.SilkS")
		)
		(fp_line
			(start -0.7874 0.4064)
			(end 0.7874 0.4064)
			(stroke
				(width 0.1524)
				(type default)
			)
			(layer "B.SilkS")
		)
		(fp_line
			(start 0.7874 -0.4064)
			(end -0.7874 -0.4064)
			(stroke
				(width 0.1524)
				(type default)
			)
			(layer "B.SilkS")
		)
		(fp_line
			(start 0.7874 0.4064)
			(end 0.7874 -0.4064)
			(stroke
				(width 0.1524)
				(type default)
			)
			(layer "B.SilkS")
		)
		(fp_line
			(start -0.67945 -0.3048)
			(end -0.67945 0.3048)
			(stroke
				(width 0.1)
				(type default)
			)
			(layer "B.Fab")
		)
		(fp_line
			(start -0.67945 0.3048)
			(end -0.120396 0.3048)
			(stroke
				(width 0.1)
				(type default)
			)
			(layer "B.Fab")
		)
		(fp_line
			(start -0.12065 -0.3048)
			(end -0.67945 -0.3048)
			(stroke
				(width 0.1)
				(type default)
			)
			(layer "B.Fab")
		)
		(fp_line
			(start -0.12065 -0.2794)
			(end -0.12065 -0.3048)
			(stroke
				(width 0.1)
				(type default)
			)
			(layer "B.Fab")
		)
		(fp_line
			(start -0.120396 0.2794)
			(end 0.12065 0.2794)
			(stroke
				(width 0.1)
				(type default)
			)
			(layer "B.Fab")
		)
		(fp_line
			(start -0.120396 0.3048)
			(end -0.120396 0.2794)
			(stroke
				(width 0.1)
				(type default)
			)
			(layer "B.Fab")
		)
		(fp_line
			(start 0.12065 -0.305054)
			(end 0.12065 -0.2794)
			(stroke
				(width 0.1)
				(type default)
			)
			(layer "B.Fab")
		)
		(fp_line
			(start 0.12065 -0.2794)
			(end -0.12065 -0.2794)
			(stroke
				(width 0.1)
				(type default)
			)
			(layer "B.Fab")
		)
		(fp_line
			(start 0.12065 0.2794)
			(end 0.12065 0.3048)
			(stroke
				(width 0.1)
				(type default)
			)
			(layer "B.Fab")
		)
		(fp_line
			(start 0.12065 0.3048)
			(end 0.67945 0.3048)
			(stroke
				(width 0.1)
				(type default)
			)
			(layer "B.Fab")
		)
		(fp_line
			(start 0.67945 -0.305054)
			(end 0.12065 -0.305054)
			(stroke
				(width 0.1)
				(type default)
			)
			(layer "B.Fab")
		)
		(fp_line
			(start 0.67945 0.3048)
			(end 0.67945 -0.305054)
			(stroke
				(width 0.1)
				(type default)
			)
			(layer "B.Fab")
		)
		(pad "1" smd circle
			(at 0.40005 0 180)
			(size 0 0)
			(layers "B.Cu" "B.Mask" "B.Paste")
			(net "PVDDCR_SOC_P0")
		)
		(pad "2" smd circle
			(at -0.40005 0 180)
			(size 0 0)
			(layers "B.Cu" "B.Mask" "B.Paste")
			(net "GND")
		)
	)
	(footprint ""
		(layer "B.Cu")
		(at 124.373386 -262.82523)
		(property "Reference" "C2444"
			(at 0 0 0)
			(layer "B.SilkS")
			(hide yes)
			(effects
				(font
					(size 1.27 1.27)
				)
				(justify mirror)
			)
		)
		(property "Value" ""
			(at 0 0 0)
			(layer "B.Fab")
			(effects
				(font
					(size 1.27 1.27)
				)
				(justify mirror)
			)
		)
		(duplicate_pad_numbers_are_jumpers no)
		(fp_line
			(start -0.7874 -0.4064)
			(end -0.7874 0.4064)
			(stroke
				(width 0.1524)
				(type default)
			)
			(layer "B.SilkS")
		)
		(fp_line
			(start -0.7874 0.4064)
			(end 0.7874 0.4064)
			(stroke
				(width 0.1524)
				(type default)
			)
			(layer "B.SilkS")
		)
		(fp_line
			(start 0.7874 -0.4064)
			(end -0.7874 -0.4064)
			(stroke
				(width 0.1524)
				(type default)
			)
			(layer "B.SilkS")
		)
		(fp_line
			(start 0.7874 0.4064)
			(end 0.7874 -0.4064)
			(stroke
				(width 0.1524)
				(type default)
			)
			(layer "B.SilkS")
		)
		(fp_line
			(start -0.67945 -0.3048)
			(end -0.67945 0.3048)
			(stroke
				(width 0.1)
				(type default)
			)
			(layer "B.Fab")
		)
		(fp_line
			(start -0.67945 0.3048)
			(end -0.120396 0.3048)
			(stroke
				(width 0.1)
				(type default)
			)
			(layer "B.Fab")
		)
		(fp_line
			(start -0.12065 -0.3048)
			(end -0.67945 -0.3048)
			(stroke
				(width 0.1)
				(type default)
			)
			(layer "B.Fab")
		)
		(fp_line
			(start -0.12065 -0.2794)
			(end -0.12065 -0.3048)
			(stroke
				(width 0.1)
				(type default)
			)
			(layer "B.Fab")
		)
		(fp_line
			(start -0.120396 0.2794)
			(end 0.12065 0.2794)
			(stroke
				(width 0.1)
				(type default)
			)
			(layer "B.Fab")
		)
		(fp_line
			(start -0.120396 0.3048)
			(end -0.120396 0.2794)
			(stroke
				(width 0.1)
				(type default)
			)
			(layer "B.Fab")
		)
		(fp_line
			(start 0.12065 -0.305054)
			(end 0.12065 -0.2794)
			(stroke
				(width 0.1)
				(type default)
			)
			(layer "B.Fab")
		)
		(fp_line
			(start 0.12065 -0.2794)
			(end -0.12065 -0.2794)
			(stroke
				(width 0.1)
				(type default)
			)
			(layer "B.Fab")
		)
		(fp_line
			(start 0.12065 0.2794)
			(end 0.12065 0.3048)
			(stroke
				(width 0.1)
				(type default)
			)
			(layer "B.Fab")
		)
		(fp_line
			(start 0.12065 0.3048)
			(end 0.67945 0.3048)
			(stroke
				(width 0.1)
				(type default)
			)
			(layer "B.Fab")
		)
		(fp_line
			(start 0.67945 -0.305054)
			(end 0.12065 -0.305054)
			(stroke
				(width 0.1)
				(type default)
			)
			(layer "B.Fab")
		)
		(fp_line
			(start 0.67945 0.3048)
			(end 0.67945 -0.305054)
			(stroke
				(width 0.1)
				(type default)
			)
			(layer "B.Fab")
		)
		(pad "1" smd circle
			(at 0.40005 0 180)
			(size 0 0)
			(layers "B.Cu" "B.Mask" "B.Paste")
			(net "PVDDCR_SOC_P1")
		)
		(pad "2" smd circle
			(at -0.40005 0 180)
			(size 0 0)
			(layers "B.Cu" "B.Mask" "B.Paste")
			(net "GND")
		)
	)
	(footprint ""
		(layer "B.Cu")
		(at 215.0618 -340.868)
		(property "Reference" "R873"
			(at 0 0 0)
			(layer "B.SilkS")
			(hide yes)
			(effects
				(font
					(size 1.27 1.27)
				)
				(justify mirror)
			)
		)
		(property "Value" ""
			(at 0 0 0)
			(layer "B.Fab")
			(effects
				(font
					(size 1.27 1.27)
				)
				(justify mirror)
			)
		)
		(duplicate_pad_numbers_are_jumpers no)
		(fp_line
			(start -0.32512 -0.175006)
			(end -0.32512 0.175006)
			(stroke
				(width 0.1)
				(type default)
			)
			(layer "B.Fab")
		)
		(fp_line
			(start -0.32512 0.175006)
			(end 0.32512 0.175006)
			(stroke
				(width 0.1)
				(type default)
			)
			(layer "B.Fab")
		)
		(fp_line
			(start 0.32512 -0.175006)
			(end -0.32512 -0.175006)
			(stroke
				(width 0.1)
				(type default)
			)
			(layer "B.Fab")
		)
		(fp_line
			(start 0.32512 0.175006)
			(end 0.32512 -0.175006)
			(stroke
				(width 0.1)
				(type default)
			)
			(layer "B.Fab")
		)
		(pad "1" smd rect
			(at 0.2667 0 180)
			(size 0.3048 0.381)
			(layers "B.Cu" "B.Mask" "B.Paste")
			(net "SMB_RT_CPU1_P2_R_SDA")
		)
		(pad "2" smd rect
			(at -0.2667 0)
			(size 0.3048 0.381)
			(layers "B.Cu" "B.Mask" "B.Paste")
			(net "SMB_RT_CPU1_P2_R2_SDA")
		)
	)
)
